FILE_TYPE = MACRO_DRAWING;
SET COLOR_WIRE YELLOW;
SET COLOR_PROP MONO;
SET COLOR_DOT WHITE;
SET COLOR_ARC YELLOW;
SET COLOR_BODY GREEN;
SET COLOR_NOTE MONO;
SET PROP_DISPLAY VALUE;
SET PAGE_NUMBER P256;
FORCEADD INTEL_CORP_BPAGE..1
(-1500 1800);
FORCEPROP 1 LAST CDS_CON_LAST_MODIFIED Fri Jun 16 17:49:35 2017
J 0
(-2925 2125);
PAINT ORANGE (-2925 2125);
DISPLAY INVISIBLE (-2925 2125);
FORCEPROP 2 LAST CUSTOM_TXT_CDS <XR_PAGE_TITLE>
J 0
(-9390 7050);
DISPLAY 0.638298 (-9390 7050);
PAINT PINK (-9390 7050);
DISPLAY INVISIBLE (-9390 7050);
FORCEPROP 2 LAST CUSTOM_TXT_CDS <CON_LAST_MODIFIED>
J 0
(-5500 1900);
PAINT ORANGE (-5500 1900);
FORCEPROP 2 LAST CUSTOM_TXT_CDS <CURRENT_DESIGN_SHEET> OF <TOTAL_DESIGN_SHEETS>
J 0
(-1975 1825);
PAINT ORANGE (-1975 1825);
FORCEPROP 1 LAST SCH_TITLE UART BLOCK DIAGRAM
J 0
(-9450 1850);
DISPLAY 2.468085 (-9450 1850);
PAINT ORANGE (-9450 1850);
FORCEPROP 2 LAST PAGE_BORDER TRUE
J 0
(-9390 7050);
DISPLAY 0.638298 (-9390 7050);
PAINT PINK (-9390 7050);
DISPLAY INVISIBLE (-9390 7050);
FORCEPROP 2 LAST CDS_LIB mstr_symbols
J 0
(-1500 1800);
PAINT MONO (-1500 1800);
DISPLAY INVISIBLE (-1500 1800);
FORCEPROP 1 LAST COMMENT_BODY TRUE
J 0
(-1488 1812);
DISPLAY 0.468085 (-1488 1812);
PAINT GREEN (-1488 1812);
DISPLAY INVISIBLE (-1488 1812);
FORCEPROP 2 LAST CDS_XR_PAGE_TITLE CR-261 : @BASEBOARD_FAB2_LIB.BASEBOARD_FAB2(SCH_1):PAGE261
J 0
(-9390 7050);
DISPLAY 0.638298 (-9390 7050);
PAINT PINK (-9390 7050);
DISPLAY INVISIBLE (-9390 7050);
FORCENOTE
$CDS_IMAGE|UART Block diagram_20160314.jpg|6666|5000
(-5500 4500) 0;
DISPLAY LEFT (-5500 4500);
QUIT
